# SCM (Grand Teton) — schematic netlist excerpt (pin names and nets, part order shuffled) for the footprints in the layout excerpt that follows; sources: Cadence DE-HDL packaged netlist, KiCad conversion of 12092022_DA0F0TMDCD0_F0T_Management_Board_D_brd_V3_OCP.brd

R331  Q_RES  120 1% CHIP  pkg 0402LF  page 20 : A = GND ; B = M_BMC_DDR4_MA<5>
R876  Q_RES  0 5% EMPTY  pkg 0402LF  page 55 : A = PWRGD_P3V3_RGM_R3 ; B = EN_P1V2_AUX_R

(kicad_pcb
	(version 20260206)
	(generator "pcbnew")
	(generator_version "10.0")
	(general
		(thickness 1.6)
		(legacy_teardrops no)
	)
	(paper "A4")
	(title_block
		(title "12092022_DA0F0TMDCD0_F0T_Management_Board_D_brd_V3_OCP.brd")
		(comment 1 "Grand Teton / footprints 414-415 of 1440")
	)
	(layers
		(0 "F.Cu" signal "TOP")
		(4 "In1.Cu" signal "GND")
		(6 "In2.Cu" signal "IN1")
		(8 "In3.Cu" signal "GND1")
		(10 "In4.Cu" signal "IN2")
		(12 "In5.Cu" signal "VCC")
		(14 "In6.Cu" signal "VCC1")
		(16 "In7.Cu" signal "IN3")
		(18 "In8.Cu" signal "GND2")
		(20 "In9.Cu" signal "IN4")
		(22 "In10.Cu" signal "GND3")
		(2 "B.Cu" signal "BOTTOM")
		(9 "F.Adhes" user "F.Adhesive")
		(11 "B.Adhes" user "B.Adhesive")
		(13 "F.Paste" user "Package Geometry/Pastemask Top")
		(15 "B.Paste" user "Package Geometry/Pastemask Bottom")
		(5 "F.SilkS" user "Ref Des/Silkscreen Top")
		(7 "B.SilkS" user "Ref Des/Silkscreen Bottom")
		(1 "F.Mask" user "Board Geometry/Soldermask Top")
		(3 "B.Mask" user "Board Geometry/Soldermask Bottom")
		(17 "Dwgs.User" user "User.Drawings")
		(19 "Cmts.User" user "User.Comments")
		(21 "Eco1.User" user "User.Eco1")
		(23 "Eco2.User" user "User.Eco2")
		(25 "Edge.Cuts" user "Board Geometry/Outline")
		(27 "Margin" user)
		(31 "F.CrtYd" user "Package Geometry/Place Bound Top")
		(29 "B.CrtYd" user "Package Geometry/Place Bound Bottom")
		(35 "F.Fab" user "Ref Des/Assembly Top")
		(33 "B.Fab" user "Ref Des/Assembly Bottom")
	)
	(footprint ""
		(layer "F.Cu")
		(at 85.29955 -45.697394 180)
		(property "Reference" "R331"
			(at 0 0 180)
			(layer "F.SilkS")
			(hide yes)
			(effects
				(font
					(size 1.27 1.27)
				)
			)
		)
		(property "Value" ""
			(at 0 0 180)
			(layer "F.Fab")
			(effects
				(font
					(size 1.27 1.27)
				)
			)
		)
		(duplicate_pad_numbers_are_jumpers no)
		(fp_line
			(start 0.7874 0.4064)
			(end -0.7874 0.4064)
			(stroke
				(width 0.1524)
				(type default)
			)
			(layer "F.SilkS")
		)
		(fp_line
			(start 0.7874 -0.4064)
			(end 0.7874 0.4064)
			(stroke
				(width 0.1524)
				(type default)
			)
			(layer "F.SilkS")
		)
		(fp_line
			(start -0.7874 0.4064)
			(end -0.7874 -0.4064)
			(stroke
				(width 0.1524)
				(type default)
			)
			(layer "F.SilkS")
		)
		(fp_line
			(start -0.7874 -0.4064)
			(end 0.7874 -0.4064)
			(stroke
				(width 0.1524)
				(type default)
			)
			(layer "F.SilkS")
		)
		(fp_line
			(start 0.67945 0.3048)
			(end 0.120396 0.3048)
			(stroke
				(width 0.1)
				(type default)
			)
			(layer "F.Fab")
		)
		(fp_line
			(start 0.67945 -0.3048)
			(end 0.67945 0.3048)
			(stroke
				(width 0.1)
				(type default)
			)
			(layer "F.Fab")
		)
		(fp_line
			(start 0.12065 -0.2794)
			(end 0.12065 -0.3048)
			(stroke
				(width 0.1)
				(type default)
			)
			(layer "F.Fab")
		)
		(fp_line
			(start 0.12065 -0.3048)
			(end 0.67945 -0.3048)
			(stroke
				(width 0.1)
				(type default)
			)
			(layer "F.Fab")
		)
		(fp_line
			(start 0.120396 0.3048)
			(end 0.120396 0.2794)
			(stroke
				(width 0.1)
				(type default)
			)
			(layer "F.Fab")
		)
		(fp_line
			(start 0.120396 0.2794)
			(end -0.12065 0.2794)
			(stroke
				(width 0.1)
				(type default)
			)
			(layer "F.Fab")
		)
		(fp_line
			(start -0.12065 0.3048)
			(end -0.67945 0.3048)
			(stroke
				(width 0.1)
				(type default)
			)
			(layer "F.Fab")
		)
		(fp_line
			(start -0.12065 0.2794)
			(end -0.12065 0.3048)
			(stroke
				(width 0.1)
				(type default)
			)
			(layer "F.Fab")
		)
		(fp_line
			(start -0.12065 -0.2794)
			(end 0.12065 -0.2794)
			(stroke
				(width 0.1)
				(type default)
			)
			(layer "F.Fab")
		)
		(fp_line
			(start -0.12065 -0.305054)
			(end -0.12065 -0.2794)
			(stroke
				(width 0.1)
				(type default)
			)
			(layer "F.Fab")
		)
		(fp_line
			(start -0.67945 0.3048)
			(end -0.67945 -0.305054)
			(stroke
				(width 0.1)
				(type default)
			)
			(layer "F.Fab")
		)
		(fp_line
			(start -0.67945 -0.305054)
			(end -0.12065 -0.305054)
			(stroke
				(width 0.1)
				(type default)
			)
			(layer "F.Fab")
		)
		(pad "1" smd circle
			(at -0.40005 0 180)
			(size 0 0)
			(layers "F.Cu" "F.Mask" "F.Paste")
			(net "GND")
		)
		(pad "2" smd circle
			(at 0.40005 0 180)
			(size 0 0)
			(layers "F.Cu" "F.Mask" "F.Paste")
			(net "M_BMC_DDR4_MA<5>")
		)
	)
	(footprint ""
		(layer "F.Cu")
		(at 77.947774 -70.3834)
		(property "Reference" "R876"
			(at 0 0 0)
			(layer "F.SilkS")
			(hide yes)
			(effects
				(font
					(size 1.27 1.27)
				)
			)
		)
		(property "Value" ""
			(at 0 0 0)
			(layer "F.Fab")
			(effects
				(font
					(size 1.27 1.27)
				)
			)
		)
		(duplicate_pad_numbers_are_jumpers no)
		(fp_line
			(start -0.7874 -0.4064)
			(end 0.7874 -0.4064)
			(stroke
				(width 0.1524)
				(type default)
			)
			(layer "F.SilkS")
		)
		(fp_line
			(start -0.7874 0.4064)
			(end -0.7874 -0.4064)
			(stroke
				(width 0.1524)
				(type default)
			)
			(layer "F.SilkS")
		)
		(fp_line
			(start 0.7874 -0.4064)
			(end 0.7874 0.4064)
			(stroke
				(width 0.1524)
				(type default)
			)
			(layer "F.SilkS")
		)
		(fp_line
			(start 0.7874 0.4064)
			(end -0.7874 0.4064)
			(stroke
				(width 0.1524)
				(type default)
			)
			(layer "F.SilkS")
		)
		(fp_line
			(start -0.67945 -0.305054)
			(end -0.12065 -0.305054)
			(stroke
				(width 0.1)
				(type default)
			)
			(layer "F.Fab")
		)
		(fp_line
			(start -0.67945 0.3048)
			(end -0.67945 -0.305054)
			(stroke
				(width 0.1)
				(type default)
			)
			(layer "F.Fab")
		)
		(fp_line
			(start -0.12065 -0.305054)
			(end -0.12065 -0.2794)
			(stroke
				(width 0.1)
				(type default)
			)
			(layer "F.Fab")
		)
		(fp_line
			(start -0.12065 -0.2794)
			(end 0.12065 -0.2794)
			(stroke
				(width 0.1)
				(type default)
			)
			(layer "F.Fab")
		)
		(fp_line
			(start -0.12065 0.2794)
			(end -0.12065 0.3048)
			(stroke
				(width 0.1)
				(type default)
			)
			(layer "F.Fab")
		)
		(fp_line
			(start -0.12065 0.3048)
			(end -0.67945 0.3048)
			(stroke
				(width 0.1)
				(type default)
			)
			(layer "F.Fab")
		)
		(fp_line
			(start 0.120396 0.2794)
			(end -0.12065 0.2794)
			(stroke
				(width 0.1)
				(type default)
			)
			(layer "F.Fab")
		)
		(fp_line
			(start 0.120396 0.3048)
			(end 0.120396 0.2794)
			(stroke
				(width 0.1)
				(type default)
			)
			(layer "F.Fab")
		)
		(fp_line
			(start 0.12065 -0.3048)
			(end 0.67945 -0.3048)
			(stroke
				(width 0.1)
				(type default)
			)
			(layer "F.Fab")
		)
		(fp_line
			(start 0.12065 -0.2794)
			(end 0.12065 -0.3048)
			(stroke
				(width 0.1)
				(type default)
			)
			(layer "F.Fab")
		)
		(fp_line
			(start 0.67945 -0.3048)
			(end 0.67945 0.3048)
			(stroke
				(width 0.1)
				(type default)
			)
			(layer "F.Fab")
		)
		(fp_line
			(start 0.67945 0.3048)
			(end 0.120396 0.3048)
			(stroke
				(width 0.1)
				(type default)
			)
			(layer "F.Fab")
		)
		(pad "1" smd circle
			(at -0.40005 0)
			(size 0 0)
			(layers "F.Cu" "F.Mask" "F.Paste")
			(net "PWRGD_P3V3_RGM_R3")
		)
		(pad "2" smd circle
			(at 0.40005 0)
			(size 0 0)
			(layers "F.Cu" "F.Mask" "F.Paste")
			(net "EN_P1V2_AUX_R")
		)
	)
)
